# SCM (Grand Teton) — schematic netlist excerpt (pin names and nets, part order shuffled) for the footprints in the layout excerpt that follows; sources: Cadence DE-HDL packaged netlist, KiCad conversion of 12092022_DA0F0TMDCD0_F0T_Management_Board_D_brd_V3_OCP.brd

Q9  MOSFET_NCH_DUAL  PJT138K IC  pkg SOT363XD  page 49
  S1  = GND
  G1  = ID_LED_BUF
  D1  = ID_LED_D_P3V3_AUX

PL35  Q_INDUCTOR  3.3UH/6A IND  pkg SMLF  page 52 : \1\ = SW_P3V3_AUX_SW ; \2\ = P3V3_AUX

(kicad_pcb
	(version 20260206)
	(generator "pcbnew")
	(generator_version "10.0")
	(general
		(thickness 1.6)
		(legacy_teardrops no)
	)
	(paper "A4")
	(title_block
		(title "12092022_DA0F0TMDCD0_F0T_Management_Board_D_brd_V3_OCP.brd")
		(comment 1 "Grand Teton / footprints 436-437 of 1440")
	)
	(layers
		(0 "F.Cu" signal "TOP")
		(4 "In1.Cu" signal "GND")
		(6 "In2.Cu" signal "IN1")
		(8 "In3.Cu" signal "GND1")
		(10 "In4.Cu" signal "IN2")
		(12 "In5.Cu" signal "VCC")
		(14 "In6.Cu" signal "VCC1")
		(16 "In7.Cu" signal "IN3")
		(18 "In8.Cu" signal "GND2")
		(20 "In9.Cu" signal "IN4")
		(22 "In10.Cu" signal "GND3")
		(2 "B.Cu" signal "BOTTOM")
		(9 "F.Adhes" user "F.Adhesive")
		(11 "B.Adhes" user "B.Adhesive")
		(13 "F.Paste" user "Package Geometry/Pastemask Top")
		(15 "B.Paste" user "Package Geometry/Pastemask Bottom")
		(5 "F.SilkS" user "Ref Des/Silkscreen Top")
		(7 "B.SilkS" user "Ref Des/Silkscreen Bottom")
		(1 "F.Mask" user "Board Geometry/Soldermask Top")
		(3 "B.Mask" user "Board Geometry/Soldermask Bottom")
		(17 "Dwgs.User" user "User.Drawings")
		(19 "Cmts.User" user "User.Comments")
		(21 "Eco1.User" user "User.Eco1")
		(23 "Eco2.User" user "User.Eco2")
		(25 "Edge.Cuts" user "Board Geometry/Outline")
		(27 "Margin" user)
		(31 "F.CrtYd" user "Package Geometry/Place Bound Top")
		(29 "B.CrtYd" user "Package Geometry/Place Bound Bottom")
		(35 "F.Fab" user "Ref Des/Assembly Top")
		(33 "B.Fab" user "Ref Des/Assembly Bottom")
	)
	(footprint ""
		(layer "F.Cu")
		(at 32.766 -10.6426)
		(property "Reference" "Q9"
			(at 1.397 1.65227 0)
			(unlocked yes)
			(layer "F.SilkS")
			(effects
				(font
					(size 0.7874 0.5842)
					(thickness 0.1524)
				)
				(justify left)
			)
		)
		(property "Value" ""
			(at 0 0 0)
			(layer "F.Fab")
			(effects
				(font
					(size 1.27 1.27)
				)
			)
		)
		(duplicate_pad_numbers_are_jumpers no)
		(fp_line
			(start -1.332738 -1.100074)
			(end -0.4826 -1.100074)
			(stroke
				(width 0.1524)
				(type default)
			)
			(layer "F.SilkS")
		)
		(fp_line
			(start -1.332738 1.100074)
			(end -1.332738 -1.100074)
			(stroke
				(width 0.1524)
				(type default)
			)
			(layer "F.SilkS")
		)
		(fp_line
			(start -0.4826 -1.100074)
			(end 0 -0.541274)
			(stroke
				(width 0.1524)
				(type default)
			)
			(layer "F.SilkS")
		)
		(fp_line
			(start 0 -0.541274)
			(end 0.4826 -1.100074)
			(stroke
				(width 0.1524)
				(type default)
			)
			(layer "F.SilkS")
		)
		(fp_line
			(start 0.4826 -1.100074)
			(end 1.332738 -1.100074)
			(stroke
				(width 0.1524)
				(type default)
			)
			(layer "F.SilkS")
		)
		(fp_line
			(start 1.332738 -1.100074)
			(end 1.332738 1.100074)
			(stroke
				(width 0.1524)
				(type default)
			)
			(layer "F.SilkS")
		)
		(fp_line
			(start 1.332738 1.100074)
			(end -1.332738 1.100074)
			(stroke
				(width 0.1524)
				(type default)
			)
			(layer "F.SilkS")
		)
		(fp_poly
			(pts
				(xy -2.169668 -1.389634) (xy -1.673352 -1.88595) (xy -1.425194 -1.141222)
			)
			(stroke
				(width 0)
				(type default)
			)
			(fill yes)
			(layer "F.SilkS")
		)
		(fp_line
			(start -0.674878 -1.100074)
			(end 0.674878 -1.100074)
			(stroke
				(width 0.1)
				(type default)
			)
			(layer "F.Fab")
		)
		(fp_line
			(start -0.674878 1.100074)
			(end -0.674878 -1.100074)
			(stroke
				(width 0.1)
				(type default)
			)
			(layer "F.Fab")
		)
		(fp_line
			(start 0.674878 -1.100074)
			(end 0.674878 1.100074)
			(stroke
				(width 0.1)
				(type default)
			)
			(layer "F.Fab")
		)
		(fp_line
			(start 0.674878 1.100074)
			(end -0.674878 1.100074)
			(stroke
				(width 0.1)
				(type default)
			)
			(layer "F.Fab")
		)
		(fp_poly
			(pts
				(xy -2.2352 -0.298958) (xy -2.2352 -1.001014) (xy -1.533144 -0.649986)
			)
			(stroke
				(width 0)
				(type default)
			)
			(fill yes)
			(layer "F.Fab")
		)
		(pad "1" smd rect
			(at -0.94996 -0.649986 90)
			(size 0.4318 0.508)
			(layers "F.Cu" "F.Mask" "F.Paste")
			(net "GND")
		)
		(pad "2" smd rect
			(at -0.94996 0 90)
			(size 0.4318 0.508)
			(layers "F.Cu" "F.Mask" "F.Paste")
			(net "ID_LED_BUF")
		)
		(pad "3" smd rect
			(at -0.94996 0.649986 90)
			(size 0.4318 0.508)
			(layers "F.Cu" "F.Mask" "F.Paste")
			(net "Net_318")
		)
		(pad "4" smd rect
			(at 0.94996 0.649986 90)
			(size 0.4318 0.508)
			(layers "F.Cu" "F.Mask" "F.Paste")
			(net "Net_320")
		)
		(pad "5" smd rect
			(at 0.94996 0 90)
			(size 0.4318 0.508)
			(layers "F.Cu" "F.Mask" "F.Paste")
			(net "Net_319")
		)
		(pad "6" smd rect
			(at 0.94996 -0.649986 90)
			(size 0.4318 0.508)
			(layers "F.Cu" "F.Mask" "F.Paste")
			(net "ID_LED_D_P3V3_AUX")
		)
	)
	(footprint ""
		(layer "F.Cu")
		(at 7.17677 -72.06107 90)
		(property "Reference" "PL35"
			(at -0.90297 4.18592 90)
			(unlocked yes)
			(layer "F.SilkS")
			(effects
				(font
					(size 0.7874 0.5842)
					(thickness 0.1524)
				)
				(justify left)
			)
		)
		(property "Value" ""
			(at 0 0 90)
			(layer "F.Fab")
			(effects
				(font
					(size 1.27 1.27)
				)
			)
		)
		(duplicate_pad_numbers_are_jumpers no)
		(fp_line
			(start 3.64998 -3.350006)
			(end 3.64998 -1.8034)
			(stroke
				(width 0.1524)
				(type default)
			)
			(layer "F.SilkS")
		)
		(fp_line
			(start -3.6576 -3.350006)
			(end 3.64998 -3.350006)
			(stroke
				(width 0.1524)
				(type default)
			)
			(layer "F.SilkS")
		)
		(fp_line
			(start -3.64998 -1.8034)
			(end -3.64998 -3.350006)
			(stroke
				(width 0.1524)
				(type default)
			)
			(layer "F.SilkS")
		)
		(fp_line
			(start 3.64998 1.8034)
			(end 3.64998 3.350006)
			(stroke
				(width 0.1524)
				(type default)
			)
			(layer "F.SilkS")
		)
		(fp_line
			(start 3.64998 3.350006)
			(end -3.64998 3.350006)
			(stroke
				(width 0.1524)
				(type default)
			)
			(layer "F.SilkS")
		)
		(fp_line
			(start -3.64998 3.350006)
			(end -3.64998 1.8288)
			(stroke
				(width 0.1524)
				(type default)
			)
			(layer "F.SilkS")
		)
		(fp_line
			(start 3.64998 -3.350006)
			(end 3.64998 3.350006)
			(stroke
				(width 0.1)
				(type default)
			)
			(layer "F.Fab")
		)
		(fp_line
			(start -3.64998 -3.350006)
			(end 3.64998 -3.350006)
			(stroke
				(width 0.1)
				(type default)
			)
			(layer "F.Fab")
		)
		(fp_line
			(start 3.64998 3.350006)
			(end -3.64998 3.350006)
			(stroke
				(width 0.1)
				(type default)
			)
			(layer "F.Fab")
		)
		(fp_line
			(start -3.64998 3.350006)
			(end -3.64998 -3.350006)
			(stroke
				(width 0.1)
				(type default)
			)
			(layer "F.Fab")
		)
		(pad "1" smd rect
			(at -2.92481 0 90)
			(size 2.15392 3.302)
			(layers "F.Cu" "F.Mask" "F.Paste")
			(net "SW_P3V3_AUX_SW")
		)
		(pad "2" smd rect
			(at 2.92481 0 90)
			(size 2.15392 3.302)
			(layers "F.Cu" "F.Mask" "F.Paste")
			(net "P3V3_AUX")
		)
	)
)
